# T6G (Grand Teton) — schematic netlist excerpt (pin names and nets, part order shuffled) for the footprints in the layout excerpt that follows; sources: Cadence DE-HDL packaged netlist, KiCad conversion of 04192023_DAF0TMB3IC0_F0TG_MB_C_brd_V02_OCP.brd

PD114  DIODE_TVS  SMF14A IC  pkg SOD123F  page 146 : A = GND ; C = P12V_AUX
C2260  Q_CAP  22UF 4V 20% X6S  pkg C0402  page 72 : A = PVDDIO_P1 ; B = GND

(kicad_pcb
	(version 20260206)
	(generator "pcbnew")
	(generator_version "10.0")
	(general
		(thickness 1.6)
		(legacy_teardrops no)
	)
	(paper "A4")
	(title_block
		(title "04192023_DAF0TMB3IC0_F0TG_MB_C_brd_V02_OCP.brd")
		(comment 1 "Grand Teton / footprints 3380-3381 of 8354")
	)
	(layers
		(0 "F.Cu" signal "TOP")
		(4 "In1.Cu" signal "GND")
		(6 "In2.Cu" signal "IN1")
		(8 "In3.Cu" signal "GND1")
		(10 "In4.Cu" signal "IN2")
		(12 "In5.Cu" signal "GND2")
		(14 "In6.Cu" signal "IN3")
		(16 "In7.Cu" signal "GND3")
		(18 "In8.Cu" signal "VCC")
		(20 "In9.Cu" signal "VCC1")
		(22 "In10.Cu" signal "GND4")
		(24 "In11.Cu" signal "IN4")
		(26 "In12.Cu" signal "GND5")
		(28 "In13.Cu" signal "IN5")
		(30 "In14.Cu" signal "GND6")
		(32 "In15.Cu" signal "IN6")
		(34 "In16.Cu" signal "GND7")
		(2 "B.Cu" signal "BOTTOM")
		(9 "F.Adhes" user "F.Adhesive")
		(11 "B.Adhes" user "B.Adhesive")
		(13 "F.Paste" user "Package Geometry/Pastemask Top")
		(15 "B.Paste" user "Package Geometry/Pastemask Bottom")
		(5 "F.SilkS" user "Ref Des/Silkscreen Top")
		(7 "B.SilkS" user "Ref Des/Silkscreen Bottom")
		(1 "F.Mask" user "Board Geometry/Soldermask Top")
		(3 "B.Mask" user "Board Geometry/Soldermask Bottom")
		(17 "Dwgs.User" user "User.Drawings")
		(19 "Cmts.User" user "User.Comments")
		(21 "Eco1.User" user "User.Eco1")
		(23 "Eco2.User" user "User.Eco2")
		(25 "Edge.Cuts" user "Board Geometry/Outline")
		(27 "Margin" user)
		(31 "F.CrtYd" user "Package Geometry/Place Bound Top")
		(29 "B.CrtYd" user "Package Geometry/Place Bound Bottom")
		(35 "F.Fab" user "Ref Des/Assembly Top")
		(33 "B.Fab" user "Ref Des/Assembly Bottom")
	)
	(footprint ""
		(layer "F.Cu")
		(at 259.568696 -39.754556 90)
		(property "Reference" "PD114"
			(at -2.56032 1.848612 90)
			(unlocked yes)
			(layer "F.SilkS")
			(effects
				(font
					(size 0.7874 0.5842)
					(thickness 0.1524)
				)
				(justify left)
			)
		)
		(property "Value" ""
			(at 0 0 90)
			(layer "F.Fab")
			(effects
				(font
					(size 1.27 1.27)
				)
			)
		)
		(duplicate_pad_numbers_are_jumpers no)
		(fp_line
			(start 2.631186 -0.999998)
			(end -2.250186 -0.999998)
			(stroke
				(width 0.1524)
				(type default)
			)
			(layer "F.SilkS")
		)
		(fp_line
			(start -2.250186 -0.999998)
			(end -2.250186 0.999998)
			(stroke
				(width 0.1524)
				(type default)
			)
			(layer "F.SilkS")
		)
		(fp_line
			(start 0.381 -0.4318)
			(end 0.381 0.3302)
			(stroke
				(width 0.1524)
				(type default)
			)
			(layer "F.SilkS")
		)
		(fp_line
			(start -0.381 -0.4318)
			(end 0.381 -0.0508)
			(stroke
				(width 0.1524)
				(type default)
			)
			(layer "F.SilkS")
		)
		(fp_line
			(start 0.381 -0.0508)
			(end 0.635 -0.0508)
			(stroke
				(width 0.1524)
				(type default)
			)
			(layer "F.SilkS")
		)
		(fp_line
			(start 0.381 -0.0508)
			(end -0.381 0.3302)
			(stroke
				(width 0.1524)
				(type default)
			)
			(layer "F.SilkS")
		)
		(fp_line
			(start -0.381 -0.0508)
			(end -0.6604 -0.0508)
			(stroke
				(width 0.1524)
				(type default)
			)
			(layer "F.SilkS")
		)
		(fp_line
			(start -0.381 0.3302)
			(end -0.381 -0.4318)
			(stroke
				(width 0.1524)
				(type default)
			)
			(layer "F.SilkS")
		)
		(fp_line
			(start 2.631186 0.999998)
			(end 2.631186 -0.999998)
			(stroke
				(width 0.1524)
				(type default)
			)
			(layer "F.SilkS")
		)
		(fp_line
			(start -2.250186 0.999998)
			(end 2.631186 0.999998)
			(stroke
				(width 0.1524)
				(type default)
			)
			(layer "F.SilkS")
		)
		(fp_rect
			(start 2.1844 -0.9652)
			(end 2.6162 1.016)
			(stroke
				(width 0)
				(type default)
			)
			(fill yes)
			(layer "F.SilkS")
		)
		(fp_line
			(start 1.450086 -0.999998)
			(end -1.450086 -0.999998)
			(stroke
				(width 0.1)
				(type default)
			)
			(layer "F.Fab")
		)
		(fp_line
			(start -1.450086 -0.999998)
			(end -1.450086 0.999998)
			(stroke
				(width 0.1)
				(type default)
			)
			(layer "F.Fab")
		)
		(fp_line
			(start 1.450086 0.999998)
			(end 1.450086 -0.999998)
			(stroke
				(width 0.1)
				(type default)
			)
			(layer "F.Fab")
		)
		(fp_line
			(start -1.450086 0.999998)
			(end 1.450086 0.999998)
			(stroke
				(width 0.1)
				(type default)
			)
			(layer "F.Fab")
		)
		(fp_text user "+"
			(at -3.885946 -0.282448 90)
			(unlocked yes)
			(layer "F.SilkS")
			(effects
				(font
					(size 1.905 1.4224)
					(thickness 0.1524)
				)
				(justify left)
			)
		)
		(fp_text user "-"
			(at 2.4384 -0.22225 90)
			(unlocked yes)
			(layer "F.SilkS")
			(effects
				(font
					(size 1.905 1.4224)
					(thickness 0.1524)
				)
				(justify left)
			)
		)
		(fp_text user "-"
			(at 2.4384 -0.22225 90)
			(unlocked yes)
			(layer "F.Fab")
			(effects
				(font
					(size 1.905 1.4224)
					(thickness 0.1524)
				)
				(justify left)
			)
		)
		(fp_text user "+"
			(at -3.4798 -0.22225 90)
			(unlocked yes)
			(layer "F.Fab")
			(effects
				(font
					(size 1.905 1.4224)
					(thickness 0.1524)
				)
				(justify left)
			)
		)
		(pad "A" smd rect
			(at -1.450086 0 90)
			(size 1.3208 1.4224)
			(layers "F.Cu" "F.Mask" "F.Paste")
			(net "GND")
		)
		(pad "C" smd rect
			(at 1.450086 0 90)
			(size 1.3208 1.4224)
			(layers "F.Cu" "F.Mask" "F.Paste")
			(net "P12V_AUX")
		)
	)
	(footprint ""
		(layer "F.Cu")
		(at 105.960164 -258.405376)
		(property "Reference" "C2260"
			(at 0 0 0)
			(layer "F.SilkS")
			(hide yes)
			(effects
				(font
					(size 1.27 1.27)
				)
			)
		)
		(property "Value" ""
			(at 0 0 0)
			(layer "F.Fab")
			(effects
				(font
					(size 1.27 1.27)
				)
			)
		)
		(duplicate_pad_numbers_are_jumpers no)
		(fp_line
			(start -0.7874 -0.4064)
			(end 0.7874 -0.4064)
			(stroke
				(width 0.1524)
				(type default)
			)
			(layer "F.SilkS")
		)
		(fp_line
			(start -0.7874 0.4064)
			(end -0.7874 -0.4064)
			(stroke
				(width 0.1524)
				(type default)
			)
			(layer "F.SilkS")
		)
		(fp_line
			(start 0.7874 -0.4064)
			(end 0.7874 0.4064)
			(stroke
				(width 0.1524)
				(type default)
			)
			(layer "F.SilkS")
		)
		(fp_line
			(start 0.7874 0.4064)
			(end -0.7874 0.4064)
			(stroke
				(width 0.1524)
				(type default)
			)
			(layer "F.SilkS")
		)
		(fp_line
			(start -0.67945 -0.305054)
			(end -0.12065 -0.305054)
			(stroke
				(width 0.1)
				(type default)
			)
			(layer "F.Fab")
		)
		(fp_line
			(start -0.67945 0.3048)
			(end -0.67945 -0.305054)
			(stroke
				(width 0.1)
				(type default)
			)
			(layer "F.Fab")
		)
		(fp_line
			(start -0.12065 -0.305054)
			(end -0.12065 -0.2794)
			(stroke
				(width 0.1)
				(type default)
			)
			(layer "F.Fab")
		)
		(fp_line
			(start -0.12065 -0.2794)
			(end 0.12065 -0.2794)
			(stroke
				(width 0.1)
				(type default)
			)
			(layer "F.Fab")
		)
		(fp_line
			(start -0.12065 0.2794)
			(end -0.12065 0.3048)
			(stroke
				(width 0.1)
				(type default)
			)
			(layer "F.Fab")
		)
		(fp_line
			(start -0.12065 0.3048)
			(end -0.67945 0.3048)
			(stroke
				(width 0.1)
				(type default)
			)
			(layer "F.Fab")
		)
		(fp_line
			(start 0.120396 0.2794)
			(end -0.12065 0.2794)
			(stroke
				(width 0.1)
				(type default)
			)
			(layer "F.Fab")
		)
		(fp_line
			(start 0.120396 0.3048)
			(end 0.120396 0.2794)
			(stroke
				(width 0.1)
				(type default)
			)
			(layer "F.Fab")
		)
		(fp_line
			(start 0.12065 -0.3048)
			(end 0.67945 -0.3048)
			(stroke
				(width 0.1)
				(type default)
			)
			(layer "F.Fab")
		)
		(fp_line
			(start 0.12065 -0.2794)
			(end 0.12065 -0.3048)
			(stroke
				(width 0.1)
				(type default)
			)
			(layer "F.Fab")
		)
		(fp_line
			(start 0.67945 -0.3048)
			(end 0.67945 0.3048)
			(stroke
				(width 0.1)
				(type default)
			)
			(layer "F.Fab")
		)
		(fp_line
			(start 0.67945 0.3048)
			(end 0.120396 0.3048)
			(stroke
				(width 0.1)
				(type default)
			)
			(layer "F.Fab")
		)
		(pad "1" smd circle
			(at -0.40005 0)
			(size 0 0)
			(layers "F.Cu" "F.Mask" "F.Paste")
			(net "PVDDIO_P1")
		)
		(pad "2" smd circle
			(at 0.40005 0)
			(size 0 0)
			(layers "F.Cu" "F.Mask" "F.Paste")
			(net "GND")
		)
	)
)
